(kicad_pcb
	(version 20260206)
	(generator "pcbnew")
	(generator_version "10.0")
	(general
		(thickness 1.6)
		(legacy_teardrops no)
	)
	(paper "A4")
	(title_block
		(title "Bryce Canyon_LED_16347-1_OCP.brd")
		(comment 1 "Bryce Canyon / footprints 8-14 of 49")
	)
	(layers
		(0 "F.Cu" signal "TOP")
		(2 "B.Cu" signal "BOTTOM")
		(9 "F.Adhes" user "F.Adhesive")
		(11 "B.Adhes" user "B.Adhesive")
		(13 "F.Paste" user "Package Geometry/Pastemask Top")
		(15 "B.Paste" user "Package Geometry/Pastemask Bottom")
		(5 "F.SilkS" user "Ref Des/Silkscreen Top")
		(7 "B.SilkS" user "Ref Des/Silkscreen Bottom")
		(1 "F.Mask" user "Board Geometry/Soldermask Top")
		(3 "B.Mask" user "Board Geometry/Soldermask Bottom")
		(17 "Dwgs.User" user "User.Drawings")
		(19 "Cmts.User" user "User.Comments")
		(21 "Eco1.User" user "User.Eco1")
		(23 "Eco2.User" user "User.Eco2")
		(25 "Edge.Cuts" user "Board Geometry/Outline")
		(27 "Margin" user)
		(31 "F.CrtYd" user "Package Geometry/Place Bound Top")
		(29 "B.CrtYd" user "Package Geometry/Place Bound Bottom")
		(35 "F.Fab" user "Ref Des/Assembly Top")
		(33 "B.Fab" user "Ref Des/Assembly Bottom")
	)
	(footprint ""
		(layer "F.Cu")
		(at 124.124974 -4.999736)
		(property "Reference" ""
			(at 0 0 0)
			(layer "F.SilkS")
			(hide yes)
			(effects
				(font
					(size 1.27 1.27)
				)
			)
		)
		(property "Value" "*"
			(at -4.0767 1.0668 0)
			(unlocked yes)
			(layer "F.Fab")
			(hide yes)
			(effects
				(font
					(size 1.016 1.016)
					(thickness 0.1524)
				)
			)
		)
		(duplicate_pad_numbers_are_jumpers no)
		(fp_poly
			(pts
				(arc
					(start 3.3147 0)
					(mid -3.3147 0)
					(end 3.3147 0)
				)
			)
			(stroke
				(width 0)
				(type default)
			)
			(fill no)
			(layer "B.CrtYd")
		)
		(fp_poly
			(pts
				(arc
					(start 3.3147 0)
					(mid -3.3147 0)
					(end 3.3147 0)
				)
			)
			(stroke
				(width 0)
				(type default)
			)
			(fill no)
			(layer "F.CrtYd")
		)
		(fp_poly
			(pts
				(arc
					(start 3.3147 0)
					(mid -3.3147 0)
					(end 3.3147 0)
				)
			)
			(stroke
				(width 0)
				(type default)
			)
			(fill no)
			(layer "B.Fab")
		)
		(fp_poly
			(pts
				(arc
					(start 3.3147 0)
					(mid -3.3147 0)
					(end 3.3147 0)
				)
			)
			(stroke
				(width 0)
				(type default)
			)
			(fill no)
			(layer "F.Fab")
		)
		(pad "1" thru_hole circle
			(at 0 0)
			(size 6.0198 6.0198)
			(drill 2.5654)
			(layers "*.Cu" "*.Mask")
			(remove_unused_layers no)
			(net "Net_7")
			(clearance -1.2192)
		)
		(zone
			(layers "F.Cu" "B.Cu")
			(hatch none 0.5)
			(connect_pads
				(clearance 0)
			)
			(min_thickness 0.25)
			(keepout
				(tracks not_allowed)
				(vias allowed)
				(pads allowed)
				(copperpour not_allowed)
				(footprints allowed)
			)
			(placement
				(enabled no)
				(sheetname "")
			)
			(fill
				(thermal_gap 0.5)
				(thermal_bridge_width 0.5)
				(island_removal_mode 0)
			)
			(polygon
				(pts
					(arc
						(start 127.134874 -4.999736)
						(mid 121.115074 -4.999736)
						(end 127.134874 -4.999736)
					)
				)
			)
		)
	)
	(footprint ""
		(layer "F.Cu")
		(at 45.150024 -14.99997)
		(property "Reference" "LED2"
			(at 0 0 0)
			(layer "F.SilkS")
			(hide yes)
			(effects
				(font
					(size 1.27 1.27)
				)
			)
		)
		(property "Value" "LED-BY-19-GP"
			(at -2.132076 1.414018 0)
			(unlocked yes)
			(layer "F.Fab")
			(hide yes)
			(effects
				(font
					(size 1.016 1.016)
					(thickness 0.1524)
				)
			)
		)
		(property "Device Type" "LED-1615-4PH26"
			(at -2.132076 -0.109982 0)
			(unlocked yes)
			(layer "F.Fab")
			(hide yes)
			(effects
				(font
					(size 1.016 1.016)
					(thickness 0.1524)
				)
			)
		)
		(duplicate_pad_numbers_are_jumpers no)
		(fp_line
			(start -1.2954 0.254)
			(end -1.2954 1.6002)
			(stroke
				(width 0.508)
				(type default)
			)
			(layer "F.SilkS")
		)
		(fp_line
			(start -1.2954 1.6002)
			(end 1.2954 1.6002)
			(stroke
				(width 0.508)
				(type default)
			)
			(layer "F.SilkS")
		)
		(fp_line
			(start -1.1176 -1.4224)
			(end 1.1176 -1.4224)
			(stroke
				(width 0.1524)
				(type default)
			)
			(layer "F.SilkS")
		)
		(fp_line
			(start -1.1176 1.4224)
			(end -1.1176 -1.4224)
			(stroke
				(width 0.1524)
				(type default)
			)
			(layer "F.SilkS")
		)
		(fp_line
			(start 1.1176 -1.4224)
			(end 1.1176 1.4224)
			(stroke
				(width 0.1524)
				(type default)
			)
			(layer "F.SilkS")
		)
		(fp_line
			(start 1.1176 1.4224)
			(end -1.1176 1.4224)
			(stroke
				(width 0.1524)
				(type default)
			)
			(layer "F.SilkS")
		)
		(fp_line
			(start 1.2954 1.6002)
			(end 1.2954 0.254)
			(stroke
				(width 0.508)
				(type default)
			)
			(layer "F.SilkS")
		)
		(fp_rect
			(start -0.7493 0.8001)
			(end 0.7493 -0.8001)
			(stroke
				(width 0)
				(type default)
			)
			(fill no)
			(layer "F.CrtYd")
		)
		(fp_poly
			(pts
				(xy -1.3716 1.6764) (xy -1.3716 -1.6764) (xy 1.3716 -1.6764) (xy 1.3716 0.0635) (xy 0.7493 0.0635)
				(xy 0.7493 -0.8001) (xy -0.7493 -0.8001) (xy -0.7493 0.8001) (xy 0.7493 0.8001) (xy 0.7493 0.0762)
				(xy 1.3716 0.0762) (xy 1.3716 1.6764)
			)
			(stroke
				(width 0)
				(type default)
			)
			(fill no)
			(layer "F.CrtYd")
		)
		(fp_rect
			(start -1.3716 1.6764)
			(end 1.3716 -1.6764)
			(stroke
				(width 0)
				(type default)
			)
			(fill no)
			(layer "F.Fab")
		)
		(pad "1" smd rect
			(at 0.50038 -0.73025)
			(size 0.7112 0.8636)
			(layers "F.Cu" "F.Mask" "F.Paste")
			(net "DRV_ACT_25_31")
		)
		(pad "2" smd rect
			(at -0.50038 -0.73025)
			(size 0.7112 0.8636)
			(layers "F.Cu" "F.Mask" "F.Paste")
			(net "FLT_HDD25_31")
		)
		(pad "3" smd rect
			(at 0.50038 0.73025)
			(size 0.7112 0.8636)
			(layers "F.Cu" "F.Mask" "F.Paste")
			(net "DRV_ACT_25_31_N")
		)
		(pad "4" smd rect
			(at -0.50038 0.73025)
			(size 0.7112 0.8636)
			(layers "F.Cu" "F.Mask" "F.Paste")
			(net "FLT_HDD25_31_N")
		)
	)
	(footprint ""
		(layer "F.Cu")
		(at 139.800076 -14.99997)
		(property "Reference" "LED5"
			(at 0 0 0)
			(layer "F.SilkS")
			(hide yes)
			(effects
				(font
					(size 1.27 1.27)
				)
			)
		)
		(property "Value" "LED-BY-19-GP"
			(at -2.132076 1.414018 0)
			(unlocked yes)
			(layer "F.Fab")
			(hide yes)
			(effects
				(font
					(size 1.016 1.016)
					(thickness 0.1524)
				)
			)
		)
		(property "Device Type" "LED-1615-4PH26"
			(at -2.132076 -0.109982 0)
			(unlocked yes)
			(layer "F.Fab")
			(hide yes)
			(effects
				(font
					(size 1.016 1.016)
					(thickness 0.1524)
				)
			)
		)
		(duplicate_pad_numbers_are_jumpers no)
		(fp_line
			(start -1.2954 0.254)
			(end -1.2954 1.6002)
			(stroke
				(width 0.508)
				(type default)
			)
			(layer "F.SilkS")
		)
		(fp_line
			(start -1.2954 1.6002)
			(end 1.2954 1.6002)
			(stroke
				(width 0.508)
				(type default)
			)
			(layer "F.SilkS")
		)
		(fp_line
			(start -1.1176 -1.4224)
			(end 1.1176 -1.4224)
			(stroke
				(width 0.1524)
				(type default)
			)
			(layer "F.SilkS")
		)
		(fp_line
			(start -1.1176 1.4224)
			(end -1.1176 -1.4224)
			(stroke
				(width 0.1524)
				(type default)
			)
			(layer "F.SilkS")
		)
		(fp_line
			(start 1.1176 -1.4224)
			(end 1.1176 1.4224)
			(stroke
				(width 0.1524)
				(type default)
			)
			(layer "F.SilkS")
		)
		(fp_line
			(start 1.1176 1.4224)
			(end -1.1176 1.4224)
			(stroke
				(width 0.1524)
				(type default)
			)
			(layer "F.SilkS")
		)
		(fp_line
			(start 1.2954 1.6002)
			(end 1.2954 0.254)
			(stroke
				(width 0.508)
				(type default)
			)
			(layer "F.SilkS")
		)
		(fp_rect
			(start -0.7493 0.8001)
			(end 0.7493 -0.8001)
			(stroke
				(width 0)
				(type default)
			)
			(fill no)
			(layer "F.CrtYd")
		)
		(fp_poly
			(pts
				(xy -1.3716 1.6764) (xy -1.3716 -1.6764) (xy 1.3716 -1.6764) (xy 1.3716 0.0635) (xy 0.7493 0.0635)
				(xy 0.7493 -0.8001) (xy -0.7493 -0.8001) (xy -0.7493 0.8001) (xy 0.7493 0.8001) (xy 0.7493 0.0762)
				(xy 1.3716 0.0762) (xy 1.3716 1.6764)
			)
			(stroke
				(width 0)
				(type default)
			)
			(fill no)
			(layer "F.CrtYd")
		)
		(fp_rect
			(start -1.3716 1.6764)
			(end 1.3716 -1.6764)
			(stroke
				(width 0)
				(type default)
			)
			(fill no)
			(layer "F.Fab")
		)
		(pad "1" smd rect
			(at 0.50038 -0.73025)
			(size 0.7112 0.8636)
			(layers "F.Cu" "F.Mask" "F.Paste")
			(net "DRV_ACT_28_34")
		)
		(pad "2" smd rect
			(at -0.50038 -0.73025)
			(size 0.7112 0.8636)
			(layers "F.Cu" "F.Mask" "F.Paste")
			(net "FLT_HDD28_34")
		)
		(pad "3" smd rect
			(at 0.50038 0.73025)
			(size 0.7112 0.8636)
			(layers "F.Cu" "F.Mask" "F.Paste")
			(net "DRV_ACT_28_34_N")
		)
		(pad "4" smd rect
			(at -0.50038 0.73025)
			(size 0.7112 0.8636)
			(layers "F.Cu" "F.Mask" "F.Paste")
			(net "FLT_HDD28_34_N")
		)
	)
	(footprint ""
		(layer "B.Cu")
		(at 138.811 -3.302 -90)
		(property "Reference" "R21"
			(at 0 0 90)
			(layer "B.SilkS")
			(hide yes)
			(effects
				(font
					(size 1.27 1.27)
				)
				(justify mirror)
			)
		)
		(property "Value" "4K7R2F-GP"
			(at -0.064008 -3.993896 270)
			(unlocked yes)
			(layer "B.Fab")
			(hide yes)
			(effects
				(font
					(size 1.016 1.016)
					(thickness 0.1524)
				)
				(justify mirror)
			)
		)
		(property "Device Type" "R402H16"
			(at -0.064008 -5.517896 270)
			(unlocked yes)
			(layer "B.Fab")
			(hide yes)
			(effects
				(font
					(size 1.016 1.016)
					(thickness 0.1524)
				)
				(justify mirror)
			)
		)
		(duplicate_pad_numbers_are_jumpers no)
		(fp_line
			(start -0.508 -0.9398)
			(end 0.508 -0.9398)
			(stroke
				(width 0.1524)
				(type default)
			)
			(layer "B.SilkS")
		)
		(fp_line
			(start 0.508 -0.9398)
			(end 0.508 0.9398)
			(stroke
				(width 0.1524)
				(type default)
			)
			(layer "B.SilkS")
		)
		(fp_rect
			(start 0.508 0.9398)
			(end -0.508 -0.9398)
			(stroke
				(width 0)
				(type default)
			)
			(fill no)
			(layer "B.CrtYd")
		)
		(fp_rect
			(start 0.508 0.9398)
			(end -0.508 -0.9398)
			(stroke
				(width 0)
				(type default)
			)
			(fill no)
			(layer "B.Fab")
		)
		(pad "1" smd custom
			(at 0 -0.4445 90)
			(size 0.1397 0.1397)
			(layers "B.Cu" "B.Mask" "B.Paste")
			(net "DRIVE_A_28_34_FLT_LED")
			(options
				(clearance outline)
				(anchor circle)
			)
			(primitives
				(gr_poly
					(pts
						(arc
							(start -0.1778 0.2794)
							(mid -0.249642 0.249642)
							(end -0.2794 0.1778)
						)
						(arc
							(start -0.2794 -0.1778)
							(mid -0.249642 -0.249642)
							(end -0.1778 -0.2794)
						)
						(arc
							(start 0.1778 -0.2794)
							(mid 0.249642 -0.249642)
							(end 0.2794 -0.1778)
						)
						(arc
							(start 0.2794 0.1778)
							(mid 0.249642 0.249642)
							(end 0.1778 0.2794)
						)
					)
					(width 0)
					(fill yes)
				)
			)
		)
		(pad "2" smd custom
			(at 0 0.4445 90)
			(size 0.1397 0.1397)
			(layers "B.Cu" "B.Mask" "B.Paste")
			(net "GND")
			(options
				(clearance outline)
				(anchor circle)
			)
			(primitives
				(gr_poly
					(pts
						(arc
							(start -0.1778 0.2794)
							(mid -0.249642 0.249642)
							(end -0.2794 0.1778)
						)
						(arc
							(start -0.2794 -0.1778)
							(mid -0.249642 -0.249642)
							(end -0.1778 -0.2794)
						)
						(arc
							(start 0.1778 -0.2794)
							(mid 0.249642 -0.249642)
							(end 0.2794 -0.1778)
						)
						(arc
							(start 0.2794 0.1778)
							(mid 0.249642 0.249642)
							(end 0.1778 0.2794)
						)
					)
					(width 0)
					(fill yes)
				)
			)
		)
	)
	(footprint ""
		(layer "B.Cu")
		(at 162.1282 -3.1242 -90)
		(property "Reference" "R23"
			(at 0 0 90)
			(layer "B.SilkS")
			(hide yes)
			(effects
				(font
					(size 1.27 1.27)
				)
				(justify mirror)
			)
		)
		(property "Value" "4K7R2F-GP"
			(at -0.064008 -3.993896 270)
			(unlocked yes)
			(layer "B.Fab")
			(hide yes)
			(effects
				(font
					(size 1.016 1.016)
					(thickness 0.1524)
				)
				(justify mirror)
			)
		)
		(property "Device Type" "R402H16"
			(at -0.064008 -5.517896 270)
			(unlocked yes)
			(layer "B.Fab")
			(hide yes)
			(effects
				(font
					(size 1.016 1.016)
					(thickness 0.1524)
				)
				(justify mirror)
			)
		)
		(duplicate_pad_numbers_are_jumpers no)
		(fp_line
			(start -0.508 -0.9398)
			(end 0.508 -0.9398)
			(stroke
				(width 0.1524)
				(type default)
			)
			(layer "B.SilkS")
		)
		(fp_line
			(start 0.508 -0.9398)
			(end 0.508 0.9398)
			(stroke
				(width 0.1524)
				(type default)
			)
			(layer "B.SilkS")
		)
		(fp_rect
			(start 0.508 0.9398)
			(end -0.508 -0.9398)
			(stroke
				(width 0)
				(type default)
			)
			(fill no)
			(layer "B.CrtYd")
		)
		(fp_rect
			(start 0.508 0.9398)
			(end -0.508 -0.9398)
			(stroke
				(width 0)
				(type default)
			)
			(fill no)
			(layer "B.Fab")
		)
		(pad "1" smd custom
			(at 0 -0.4445 90)
			(size 0.1397 0.1397)
			(layers "B.Cu" "B.Mask" "B.Paste")
			(net "DRIVE_A_29_35_FLT_LED")
			(options
				(clearance outline)
				(anchor circle)
			)
			(primitives
				(gr_poly
					(pts
						(arc
							(start -0.1778 0.2794)
							(mid -0.249642 0.249642)
							(end -0.2794 0.1778)
						)
						(arc
							(start -0.2794 -0.1778)
							(mid -0.249642 -0.249642)
							(end -0.1778 -0.2794)
						)
						(arc
							(start 0.1778 -0.2794)
							(mid 0.249642 -0.249642)
							(end 0.2794 -0.1778)
						)
						(arc
							(start 0.2794 0.1778)
							(mid 0.249642 0.249642)
							(end 0.1778 0.2794)
						)
					)
					(width 0)
					(fill yes)
				)
			)
		)
		(pad "2" smd custom
			(at 0 0.4445 90)
			(size 0.1397 0.1397)
			(layers "B.Cu" "B.Mask" "B.Paste")
			(net "GND")
			(options
				(clearance outline)
				(anchor circle)
			)
			(primitives
				(gr_poly
					(pts
						(arc
							(start -0.1778 0.2794)
							(mid -0.249642 0.249642)
							(end -0.2794 0.1778)
						)
						(arc
							(start -0.2794 -0.1778)
							(mid -0.249642 -0.249642)
							(end -0.1778 -0.2794)
						)
						(arc
							(start 0.1778 -0.2794)
							(mid 0.249642 -0.249642)
							(end 0.2794 -0.1778)
						)
						(arc
							(start 0.2794 0.1778)
							(mid 0.249642 0.249642)
							(end 0.1778 0.2794)
						)
					)
					(width 0)
					(fill yes)
				)
			)
		)
	)
	(footprint ""
		(layer "B.Cu")
		(at 159.512 -5.7404 180)
		(property "Reference" "R11"
			(at 0 0 0)
			(layer "B.SilkS")
			(hide yes)
			(effects
				(font
					(size 1.27 1.27)
				)
				(justify mirror)
			)
		)
		(property "Value" "130R3F-GP"
			(at 0.0254 -2.5146 180)
			(unlocked yes)
			(layer "B.Fab")
			(hide yes)
			(effects
				(font
					(size 1.016 1.016)
					(thickness 0.1524)
				)
				(justify mirror)
			)
		)
		(property "Device Type" "R603H22"
			(at 0.0254 -4.0386 180)
			(unlocked yes)
			(layer "B.Fab")
			(hide yes)
			(effects
				(font
					(size 1.016 1.016)
					(thickness 0.1524)
				)
				(justify mirror)
			)
		)
		(duplicate_pad_numbers_are_jumpers no)
		(fp_line
			(start 0.4826 0)
			(end 0.2032 0)
			(stroke
				(width 0.2032)
				(type default)
			)
			(layer "B.SilkS")
		)
		(fp_line
			(start -0.2032 0)
			(end -0.4826 0)
			(stroke
				(width 0.2032)
				(type default)
			)
			(layer "B.SilkS")
		)
		(fp_rect
			(start 0.5842 1.3335)
			(end -0.5842 -1.3335)
			(stroke
				(width 0)
				(type default)
			)
			(fill no)
			(layer "B.CrtYd")
		)
		(fp_rect
			(start 0.5842 1.3335)
			(end -0.5842 -1.3335)
			(stroke
				(width 0)
				(type default)
			)
			(fill no)
			(layer "B.Fab")
		)
		(pad "1" smd custom
			(at 0 -0.762)
			(size 0.2159 0.2159)
			(layers "B.Cu" "B.Mask" "B.Paste")
			(net "P5V_A")
			(options
				(clearance outline)
				(anchor circle)
			)
			(primitives
				(gr_poly
					(pts
						(arc
							(start -0.3302 0.4318)
							(mid -0.402042 0.402042)
							(end -0.4318 0.3302)
						)
						(arc
							(start -0.4318 -0.3302)
							(mid -0.402042 -0.402042)
							(end -0.3302 -0.4318)
						)
						(arc
							(start 0.3302 -0.4318)
							(mid 0.402042 -0.402042)
							(end 0.4318 -0.3302)
						)
						(arc
							(start 0.4318 0.3302)
							(mid 0.402042 0.402042)
							(end 0.3302 0.4318)
						)
					)
					(width 0)
					(fill yes)
				)
			)
		)
		(pad "2" smd custom
			(at 0 0.762)
			(size 0.2159 0.2159)
			(layers "B.Cu" "B.Mask" "B.Paste")
			(net "FLT_HDD29_35")
			(options
				(clearance outline)
				(anchor circle)
			)
			(primitives
				(gr_poly
					(pts
						(arc
							(start -0.3302 0.4318)
							(mid -0.402042 0.402042)
							(end -0.4318 0.3302)
						)
						(arc
							(start -0.4318 -0.3302)
							(mid -0.402042 -0.402042)
							(end -0.3302 -0.4318)
						)
						(arc
							(start 0.3302 -0.4318)
							(mid 0.402042 -0.402042)
							(end 0.4318 -0.3302)
						)
						(arc
							(start 0.4318 0.3302)
							(mid 0.402042 0.402042)
							(end 0.3302 0.4318)
						)
					)
					(width 0)
					(fill yes)
				)
			)
		)
	)
	(footprint ""
		(layer "B.Cu")
		(at 64.696594 -3.24358 -90)
		(property "Reference" "R18"
			(at 0 0 90)
			(layer "B.SilkS")
			(hide yes)
			(effects
				(font
					(size 1.27 1.27)
				)
				(justify mirror)
			)
		)
		(property "Value" "4K7R2F-GP"
			(at -0.064008 -3.993896 270)
			(unlocked yes)
			(layer "B.Fab")
			(hide yes)
			(effects
				(font
					(size 1.016 1.016)
					(thickness 0.1524)
				)
				(justify mirror)
			)
		)
		(property "Device Type" "R402H16"
			(at -0.064008 -5.517896 270)
			(unlocked yes)
			(layer "B.Fab")
			(hide yes)
			(effects
				(font
					(size 1.016 1.016)
					(thickness 0.1524)
				)
				(justify mirror)
			)
		)
		(duplicate_pad_numbers_are_jumpers no)
		(fp_line
			(start -0.508 -0.9398)
			(end 0.508 -0.9398)
			(stroke
				(width 0.1524)
				(type default)
			)
			(layer "B.SilkS")
		)
		(fp_line
			(start 0.508 -0.9398)
			(end 0.508 0.9398)
			(stroke
				(width 0.1524)
				(type default)
			)
			(layer "B.SilkS")
		)
		(fp_rect
			(start 0.508 0.9398)
			(end -0.508 -0.9398)
			(stroke
				(width 0)
				(type default)
			)
			(fill no)
			(layer "B.CrtYd")
		)
		(fp_rect
			(start 0.508 0.9398)
			(end -0.508 -0.9398)
			(stroke
				(width 0)
				(type default)
			)
			(fill no)
			(layer "B.Fab")
		)
		(pad "1" smd custom
			(at 0 -0.4445 90)
			(size 0.1397 0.1397)
			(layers "B.Cu" "B.Mask" "B.Paste")
			(net "DRIVE_A_26_32_ACT")
			(options
				(clearance outline)
				(anchor circle)
			)
			(primitives
				(gr_poly
					(pts
						(arc
							(start -0.1778 0.2794)
							(mid -0.249642 0.249642)
							(end -0.2794 0.1778)
						)
						(arc
							(start -0.2794 -0.1778)
							(mid -0.249642 -0.249642)
							(end -0.1778 -0.2794)
						)
						(arc
							(start 0.1778 -0.2794)
							(mid 0.249642 -0.249642)
							(end 0.2794 -0.1778)
						)
						(arc
							(start 0.2794 0.1778)
							(mid 0.249642 0.249642)
							(end 0.1778 0.2794)
						)
					)
					(width 0)
					(fill yes)
				)
			)
		)
		(pad "2" smd custom
			(at 0 0.4445 90)
			(size 0.1397 0.1397)
			(layers "B.Cu" "B.Mask" "B.Paste")
			(net "GND")
			(options
				(clearance outline)
				(anchor circle)
			)
			(primitives
				(gr_poly
					(pts
						(arc
							(start -0.1778 0.2794)
							(mid -0.249642 0.249642)
							(end -0.2794 0.1778)
						)
						(arc
							(start -0.2794 -0.1778)
							(mid -0.249642 -0.249642)
							(end -0.1778 -0.2794)
						)
						(arc
							(start 0.1778 -0.2794)
							(mid 0.249642 -0.249642)
							(end 0.2794 -0.1778)
						)
						(arc
							(start 0.2794 0.1778)
							(mid 0.249642 0.249642)
							(end 0.1778 0.2794)
						)
					)
					(width 0)
					(fill yes)
				)
			)
		)
	)
)
